FILE_TYPE = CONNECTIVITY;
{Allegro Design Entry HDL 16.6-p007 (v16-6-112F) 10/10/2012}
"PAGE_NUMBER" = 174;
0"NC";
END.
